# T6G (Grand Teton) — schematic netlist excerpt (pin names and nets, part order shuffled) for the footprints in the layout excerpt that follows; sources: Cadence DE-HDL packaged netlist, KiCad conversion of 04192023_DAF0TMB3IC0_F0TG_MB_C_brd_V02_OCP.brd

PC582_SOP0_2  Q_CAP  2.2UF 10V 10% X6S  pkg C0402  page 198 : A = PVDDCR_CPU0_P0_PVCC ; B = GND
PR515  Q_RES  1.5 1% EMPTY  pkg 0402LF  page 219 : A = SW_PVDDCR_CPU1_P1_SW4_RC ; B = GND

(kicad_pcb
	(version 20260206)
	(generator "pcbnew")
	(generator_version "10.0")
	(general
		(thickness 1.6)
		(legacy_teardrops no)
	)
	(paper "A4")
	(title_block
		(title "04192023_DAF0TMB3IC0_F0TG_MB_C_brd_V02_OCP.brd")
		(comment 1 "Grand Teton / footprints 3791-3792 of 8354")
	)
	(layers
		(0 "F.Cu" signal "TOP")
		(4 "In1.Cu" signal "GND")
		(6 "In2.Cu" signal "IN1")
		(8 "In3.Cu" signal "GND1")
		(10 "In4.Cu" signal "IN2")
		(12 "In5.Cu" signal "GND2")
		(14 "In6.Cu" signal "IN3")
		(16 "In7.Cu" signal "GND3")
		(18 "In8.Cu" signal "VCC")
		(20 "In9.Cu" signal "VCC1")
		(22 "In10.Cu" signal "GND4")
		(24 "In11.Cu" signal "IN4")
		(26 "In12.Cu" signal "GND5")
		(28 "In13.Cu" signal "IN5")
		(30 "In14.Cu" signal "GND6")
		(32 "In15.Cu" signal "IN6")
		(34 "In16.Cu" signal "GND7")
		(2 "B.Cu" signal "BOTTOM")
		(9 "F.Adhes" user "F.Adhesive")
		(11 "B.Adhes" user "B.Adhesive")
		(13 "F.Paste" user "Package Geometry/Pastemask Top")
		(15 "B.Paste" user "Package Geometry/Pastemask Bottom")
		(5 "F.SilkS" user "Ref Des/Silkscreen Top")
		(7 "B.SilkS" user "Ref Des/Silkscreen Bottom")
		(1 "F.Mask" user "Board Geometry/Soldermask Top")
		(3 "B.Mask" user "Board Geometry/Soldermask Bottom")
		(17 "Dwgs.User" user "User.Drawings")
		(19 "Cmts.User" user "User.Comments")
		(21 "Eco1.User" user "User.Eco1")
		(23 "Eco2.User" user "User.Eco2")
		(25 "Edge.Cuts" user "Board Geometry/Outline")
		(27 "Margin" user)
		(31 "F.CrtYd" user "Package Geometry/Place Bound Top")
		(29 "B.CrtYd" user "Package Geometry/Place Bound Bottom")
		(35 "F.Fab" user "Ref Des/Assembly Top")
		(33 "B.Fab" user "Ref Des/Assembly Bottom")
	)
	(footprint ""
		(layer "F.Cu")
		(at 58.197496 -344.986864 90)
		(property "Reference" "PR515"
			(at 0 0 90)
			(layer "F.SilkS")
			(hide yes)
			(effects
				(font
					(size 1.27 1.27)
				)
			)
		)
		(property "Value" ""
			(at 0 0 90)
			(layer "F.Fab")
			(effects
				(font
					(size 1.27 1.27)
				)
			)
		)
		(duplicate_pad_numbers_are_jumpers no)
		(fp_line
			(start 0.7874 -0.4064)
			(end 0.7874 0.4064)
			(stroke
				(width 0.1524)
				(type default)
			)
			(layer "F.SilkS")
		)
		(fp_line
			(start -0.7874 -0.4064)
			(end 0.7874 -0.4064)
			(stroke
				(width 0.1524)
				(type default)
			)
			(layer "F.SilkS")
		)
		(fp_line
			(start 0.7874 0.4064)
			(end -0.7874 0.4064)
			(stroke
				(width 0.1524)
				(type default)
			)
			(layer "F.SilkS")
		)
		(fp_line
			(start -0.7874 0.4064)
			(end -0.7874 -0.4064)
			(stroke
				(width 0.1524)
				(type default)
			)
			(layer "F.SilkS")
		)
		(fp_line
			(start -0.12065 -0.305054)
			(end -0.12065 -0.2794)
			(stroke
				(width 0.1)
				(type default)
			)
			(layer "F.Fab")
		)
		(fp_line
			(start -0.67945 -0.305054)
			(end -0.12065 -0.305054)
			(stroke
				(width 0.1)
				(type default)
			)
			(layer "F.Fab")
		)
		(fp_line
			(start 0.67945 -0.3048)
			(end 0.67945 0.3048)
			(stroke
				(width 0.1)
				(type default)
			)
			(layer "F.Fab")
		)
		(fp_line
			(start 0.12065 -0.3048)
			(end 0.67945 -0.3048)
			(stroke
				(width 0.1)
				(type default)
			)
			(layer "F.Fab")
		)
		(fp_line
			(start 0.12065 -0.2794)
			(end 0.12065 -0.3048)
			(stroke
				(width 0.1)
				(type default)
			)
			(layer "F.Fab")
		)
		(fp_line
			(start -0.12065 -0.2794)
			(end 0.12065 -0.2794)
			(stroke
				(width 0.1)
				(type default)
			)
			(layer "F.Fab")
		)
		(fp_line
			(start 0.120396 0.2794)
			(end -0.12065 0.2794)
			(stroke
				(width 0.1)
				(type default)
			)
			(layer "F.Fab")
		)
		(fp_line
			(start -0.12065 0.2794)
			(end -0.12065 0.3048)
			(stroke
				(width 0.1)
				(type default)
			)
			(layer "F.Fab")
		)
		(fp_line
			(start 0.67945 0.3048)
			(end 0.120396 0.3048)
			(stroke
				(width 0.1)
				(type default)
			)
			(layer "F.Fab")
		)
		(fp_line
			(start 0.120396 0.3048)
			(end 0.120396 0.2794)
			(stroke
				(width 0.1)
				(type default)
			)
			(layer "F.Fab")
		)
		(fp_line
			(start -0.12065 0.3048)
			(end -0.67945 0.3048)
			(stroke
				(width 0.1)
				(type default)
			)
			(layer "F.Fab")
		)
		(fp_line
			(start -0.67945 0.3048)
			(end -0.67945 -0.305054)
			(stroke
				(width 0.1)
				(type default)
			)
			(layer "F.Fab")
		)
		(pad "1" smd circle
			(at -0.40005 0 90)
			(size 0 0)
			(layers "F.Cu" "F.Mask" "F.Paste")
			(net "SW_PVDDCR_CPU1_P1_SW4_RC")
		)
		(pad "2" smd circle
			(at 0.40005 0 90)
			(size 0 0)
			(layers "F.Cu" "F.Mask" "F.Paste")
			(net "GND")
		)
	)
	(footprint ""
		(layer "F.Cu")
		(at 409.830778 -168.595548 90)
		(property "Reference" "PC582_SOP0_2"
			(at 0 0 90)
			(layer "F.SilkS")
			(hide yes)
			(effects
				(font
					(size 1.27 1.27)
				)
			)
		)
		(property "Value" ""
			(at 0 0 90)
			(layer "F.Fab")
			(effects
				(font
					(size 1.27 1.27)
				)
			)
		)
		(duplicate_pad_numbers_are_jumpers no)
		(fp_line
			(start 0.7874 -0.4064)
			(end 0.7874 0.4064)
			(stroke
				(width 0.1524)
				(type default)
			)
			(layer "F.SilkS")
		)
		(fp_line
			(start -0.7874 -0.4064)
			(end 0.7874 -0.4064)
			(stroke
				(width 0.1524)
				(type default)
			)
			(layer "F.SilkS")
		)
		(fp_line
			(start 0.7874 0.4064)
			(end -0.7874 0.4064)
			(stroke
				(width 0.1524)
				(type default)
			)
			(layer "F.SilkS")
		)
		(fp_line
			(start -0.7874 0.4064)
			(end -0.7874 -0.4064)
			(stroke
				(width 0.1524)
				(type default)
			)
			(layer "F.SilkS")
		)
		(fp_line
			(start -0.12065 -0.305054)
			(end -0.12065 -0.2794)
			(stroke
				(width 0.1)
				(type default)
			)
			(layer "F.Fab")
		)
		(fp_line
			(start -0.67945 -0.305054)
			(end -0.12065 -0.305054)
			(stroke
				(width 0.1)
				(type default)
			)
			(layer "F.Fab")
		)
		(fp_line
			(start 0.67945 -0.3048)
			(end 0.67945 0.3048)
			(stroke
				(width 0.1)
				(type default)
			)
			(layer "F.Fab")
		)
		(fp_line
			(start 0.12065 -0.3048)
			(end 0.67945 -0.3048)
			(stroke
				(width 0.1)
				(type default)
			)
			(layer "F.Fab")
		)
		(fp_line
			(start 0.12065 -0.2794)
			(end 0.12065 -0.3048)
			(stroke
				(width 0.1)
				(type default)
			)
			(layer "F.Fab")
		)
		(fp_line
			(start -0.12065 -0.2794)
			(end 0.12065 -0.2794)
			(stroke
				(width 0.1)
				(type default)
			)
			(layer "F.Fab")
		)
		(fp_line
			(start 0.120396 0.2794)
			(end -0.12065 0.2794)
			(stroke
				(width 0.1)
				(type default)
			)
			(layer "F.Fab")
		)
		(fp_line
			(start -0.12065 0.2794)
			(end -0.12065 0.3048)
			(stroke
				(width 0.1)
				(type default)
			)
			(layer "F.Fab")
		)
		(fp_line
			(start 0.67945 0.3048)
			(end 0.120396 0.3048)
			(stroke
				(width 0.1)
				(type default)
			)
			(layer "F.Fab")
		)
		(fp_line
			(start 0.120396 0.3048)
			(end 0.120396 0.2794)
			(stroke
				(width 0.1)
				(type default)
			)
			(layer "F.Fab")
		)
		(fp_line
			(start -0.12065 0.3048)
			(end -0.67945 0.3048)
			(stroke
				(width 0.1)
				(type default)
			)
			(layer "F.Fab")
		)
		(fp_line
			(start -0.67945 0.3048)
			(end -0.67945 -0.305054)
			(stroke
				(width 0.1)
				(type default)
			)
			(layer "F.Fab")
		)
		(pad "1" smd circle
			(at -0.40005 0 90)
			(size 0 0)
			(layers "F.Cu" "F.Mask" "F.Paste")
			(net "PVDDCR_CPU0_P0_PVCC")
		)
		(pad "2" smd circle
			(at 0.40005 0 90)
			(size 0 0)
			(layers "F.Cu" "F.Mask" "F.Paste")
			(net "GND")
		)
	)
)
